# SCM (Grand Teton) — schematic netlist excerpt (pin names and nets, part order shuffled) for the footprints in the layout excerpt that follows; sources: Cadence DE-HDL packaged netlist, KiCad conversion of 12092022_DA0F0TMDCD0_F0T_Management_Board_D_brd_V3_OCP.brd

R875  Q_RES  0 5% EMPTY  pkg 0402LF  page 54 : A = PWRGD_P2V5_AUX_R3 ; B = EN_P1V8_R
R565  Q_RES  100 1% CHIP  pkg 0402LF  page 15 : A = ID_RST_BTN_BMC_R_N ; B = ID_RST_BTN_BMC_N

(kicad_pcb
	(version 20260206)
	(generator "pcbnew")
	(generator_version "10.0")
	(general
		(thickness 1.6)
		(legacy_teardrops no)
	)
	(paper "A4")
	(title_block
		(title "12092022_DA0F0TMDCD0_F0T_Management_Board_D_brd_V3_OCP.brd")
		(comment 1 "Grand Teton / footprints 571-572 of 1440")
	)
	(layers
		(0 "F.Cu" signal "TOP")
		(4 "In1.Cu" signal "GND")
		(6 "In2.Cu" signal "IN1")
		(8 "In3.Cu" signal "GND1")
		(10 "In4.Cu" signal "IN2")
		(12 "In5.Cu" signal "VCC")
		(14 "In6.Cu" signal "VCC1")
		(16 "In7.Cu" signal "IN3")
		(18 "In8.Cu" signal "GND2")
		(20 "In9.Cu" signal "IN4")
		(22 "In10.Cu" signal "GND3")
		(2 "B.Cu" signal "BOTTOM")
		(9 "F.Adhes" user "F.Adhesive")
		(11 "B.Adhes" user "B.Adhesive")
		(13 "F.Paste" user "Package Geometry/Pastemask Top")
		(15 "B.Paste" user "Package Geometry/Pastemask Bottom")
		(5 "F.SilkS" user "Ref Des/Silkscreen Top")
		(7 "B.SilkS" user "Ref Des/Silkscreen Bottom")
		(1 "F.Mask" user "Board Geometry/Soldermask Top")
		(3 "B.Mask" user "Board Geometry/Soldermask Bottom")
		(17 "Dwgs.User" user "User.Drawings")
		(19 "Cmts.User" user "User.Comments")
		(21 "Eco1.User" user "User.Eco1")
		(23 "Eco2.User" user "User.Eco2")
		(25 "Edge.Cuts" user "Board Geometry/Outline")
		(27 "Margin" user)
		(31 "F.CrtYd" user "Package Geometry/Place Bound Top")
		(29 "B.CrtYd" user "Package Geometry/Place Bound Bottom")
		(35 "F.Fab" user "Ref Des/Assembly Top")
		(33 "B.Fab" user "Ref Des/Assembly Bottom")
	)
	(footprint ""
		(layer "F.Cu")
		(at 36.9824 -60.1726 -90)
		(property "Reference" "R565"
			(at 0 0 270)
			(layer "F.SilkS")
			(hide yes)
			(effects
				(font
					(size 1.27 1.27)
				)
			)
		)
		(property "Value" ""
			(at 0 0 270)
			(layer "F.Fab")
			(effects
				(font
					(size 1.27 1.27)
				)
			)
		)
		(duplicate_pad_numbers_are_jumpers no)
		(fp_line
			(start -0.7874 0.4064)
			(end -0.7874 -0.4064)
			(stroke
				(width 0.1524)
				(type default)
			)
			(layer "F.SilkS")
		)
		(fp_line
			(start 0.7874 0.4064)
			(end -0.7874 0.4064)
			(stroke
				(width 0.1524)
				(type default)
			)
			(layer "F.SilkS")
		)
		(fp_line
			(start -0.7874 -0.4064)
			(end 0.7874 -0.4064)
			(stroke
				(width 0.1524)
				(type default)
			)
			(layer "F.SilkS")
		)
		(fp_line
			(start 0.7874 -0.4064)
			(end 0.7874 0.4064)
			(stroke
				(width 0.1524)
				(type default)
			)
			(layer "F.SilkS")
		)
		(fp_line
			(start -0.67945 0.3048)
			(end -0.67945 -0.305054)
			(stroke
				(width 0.1)
				(type default)
			)
			(layer "F.Fab")
		)
		(fp_line
			(start -0.12065 0.3048)
			(end -0.67945 0.3048)
			(stroke
				(width 0.1)
				(type default)
			)
			(layer "F.Fab")
		)
		(fp_line
			(start 0.120396 0.3048)
			(end 0.120396 0.2794)
			(stroke
				(width 0.1)
				(type default)
			)
			(layer "F.Fab")
		)
		(fp_line
			(start 0.67945 0.3048)
			(end 0.120396 0.3048)
			(stroke
				(width 0.1)
				(type default)
			)
			(layer "F.Fab")
		)
		(fp_line
			(start -0.12065 0.2794)
			(end -0.12065 0.3048)
			(stroke
				(width 0.1)
				(type default)
			)
			(layer "F.Fab")
		)
		(fp_line
			(start 0.120396 0.2794)
			(end -0.12065 0.2794)
			(stroke
				(width 0.1)
				(type default)
			)
			(layer "F.Fab")
		)
		(fp_line
			(start -0.12065 -0.2794)
			(end 0.12065 -0.2794)
			(stroke
				(width 0.1)
				(type default)
			)
			(layer "F.Fab")
		)
		(fp_line
			(start 0.12065 -0.2794)
			(end 0.12065 -0.3048)
			(stroke
				(width 0.1)
				(type default)
			)
			(layer "F.Fab")
		)
		(fp_line
			(start 0.12065 -0.3048)
			(end 0.67945 -0.3048)
			(stroke
				(width 0.1)
				(type default)
			)
			(layer "F.Fab")
		)
		(fp_line
			(start 0.67945 -0.3048)
			(end 0.67945 0.3048)
			(stroke
				(width 0.1)
				(type default)
			)
			(layer "F.Fab")
		)
		(fp_line
			(start -0.67945 -0.305054)
			(end -0.12065 -0.305054)
			(stroke
				(width 0.1)
				(type default)
			)
			(layer "F.Fab")
		)
		(fp_line
			(start -0.12065 -0.305054)
			(end -0.12065 -0.2794)
			(stroke
				(width 0.1)
				(type default)
			)
			(layer "F.Fab")
		)
		(pad "1" smd circle
			(at -0.40005 0 270)
			(size 0 0)
			(layers "F.Cu" "F.Mask" "F.Paste")
			(net "ID_RST_BTN_BMC_R_N")
		)
		(pad "2" smd circle
			(at 0.40005 0 270)
			(size 0 0)
			(layers "F.Cu" "F.Mask" "F.Paste")
			(net "ID_RST_BTN_BMC_N")
		)
	)
	(footprint ""
		(layer "F.Cu")
		(at 32.69488 -57.45226 -90)
		(property "Reference" "R875"
			(at 0 0 270)
			(layer "F.SilkS")
			(hide yes)
			(effects
				(font
					(size 1.27 1.27)
				)
			)
		)
		(property "Value" ""
			(at 0 0 270)
			(layer "F.Fab")
			(effects
				(font
					(size 1.27 1.27)
				)
			)
		)
		(duplicate_pad_numbers_are_jumpers no)
		(fp_line
			(start -0.7874 0.4064)
			(end -0.7874 -0.4064)
			(stroke
				(width 0.1524)
				(type default)
			)
			(layer "F.SilkS")
		)
		(fp_line
			(start 0.7874 0.4064)
			(end -0.7874 0.4064)
			(stroke
				(width 0.1524)
				(type default)
			)
			(layer "F.SilkS")
		)
		(fp_line
			(start -0.7874 -0.4064)
			(end 0.7874 -0.4064)
			(stroke
				(width 0.1524)
				(type default)
			)
			(layer "F.SilkS")
		)
		(fp_line
			(start 0.7874 -0.4064)
			(end 0.7874 0.4064)
			(stroke
				(width 0.1524)
				(type default)
			)
			(layer "F.SilkS")
		)
		(fp_line
			(start -0.67945 0.3048)
			(end -0.67945 -0.305054)
			(stroke
				(width 0.1)
				(type default)
			)
			(layer "F.Fab")
		)
		(fp_line
			(start -0.12065 0.3048)
			(end -0.67945 0.3048)
			(stroke
				(width 0.1)
				(type default)
			)
			(layer "F.Fab")
		)
		(fp_line
			(start 0.120396 0.3048)
			(end 0.120396 0.2794)
			(stroke
				(width 0.1)
				(type default)
			)
			(layer "F.Fab")
		)
		(fp_line
			(start 0.67945 0.3048)
			(end 0.120396 0.3048)
			(stroke
				(width 0.1)
				(type default)
			)
			(layer "F.Fab")
		)
		(fp_line
			(start -0.12065 0.2794)
			(end -0.12065 0.3048)
			(stroke
				(width 0.1)
				(type default)
			)
			(layer "F.Fab")
		)
		(fp_line
			(start 0.120396 0.2794)
			(end -0.12065 0.2794)
			(stroke
				(width 0.1)
				(type default)
			)
			(layer "F.Fab")
		)
		(fp_line
			(start -0.12065 -0.2794)
			(end 0.12065 -0.2794)
			(stroke
				(width 0.1)
				(type default)
			)
			(layer "F.Fab")
		)
		(fp_line
			(start 0.12065 -0.2794)
			(end 0.12065 -0.3048)
			(stroke
				(width 0.1)
				(type default)
			)
			(layer "F.Fab")
		)
		(fp_line
			(start 0.12065 -0.3048)
			(end 0.67945 -0.3048)
			(stroke
				(width 0.1)
				(type default)
			)
			(layer "F.Fab")
		)
		(fp_line
			(start 0.67945 -0.3048)
			(end 0.67945 0.3048)
			(stroke
				(width 0.1)
				(type default)
			)
			(layer "F.Fab")
		)
		(fp_line
			(start -0.67945 -0.305054)
			(end -0.12065 -0.305054)
			(stroke
				(width 0.1)
				(type default)
			)
			(layer "F.Fab")
		)
		(fp_line
			(start -0.12065 -0.305054)
			(end -0.12065 -0.2794)
			(stroke
				(width 0.1)
				(type default)
			)
			(layer "F.Fab")
		)
		(pad "1" smd circle
			(at -0.40005 0 270)
			(size 0 0)
			(layers "F.Cu" "F.Mask" "F.Paste")
			(net "PWRGD_P2V5_AUX_R3")
		)
		(pad "2" smd circle
			(at 0.40005 0 270)
			(size 0 0)
			(layers "F.Cu" "F.Mask" "F.Paste")
			(net "EN_P1V8_R")
		)
	)
)
